# BASEBOARD_FAB2 (Tioga Pass) — schematic netlist excerpt (pin names and nets, part order shuffled) for the footprints in the layout excerpt that follows; sources: Cadence DE-HDL packaged netlist, KiCad conversion of Wiwynn_Tioga_Pass_MB.brd

R12W1  665KR5B-1-GP  0.1%  pkg SMD-RG3  page 197 : \1\ = P12V_STBY ; \2\ = VR_PVDDQ_ABC_AIINSEN
R25W170  RES  1.00K 1% CHIP  pkg 0402  page 254 : A = JTAG_BMC_TRST_BUF_N ; B = GND
R4D25  RES  27.4 1% CHIP  pkg 0402  page 103 : A = CLK_100M_CPU0_BCLK0_R_DN ; B = CLK_100M_CPU0_BCLK0_DN

(kicad_pcb
	(version 20260206)
	(generator "pcbnew")
	(generator_version "10.0")
	(general
		(thickness 1.6)
		(legacy_teardrops no)
	)
	(paper "A4")
	(title_block
		(title "Wiwynn_Tioga_Pass_MB.brd")
		(comment 1 "Tioga Pass / footprints 2318-2320 of 4770")
	)
	(layers
		(0 "F.Cu" signal "TOP")
		(4 "In1.Cu" signal "L2GND")
		(6 "In2.Cu" signal "L3")
		(8 "In3.Cu" signal "L4GND")
		(10 "In4.Cu" signal "L5")
		(12 "In5.Cu" signal "L6GND")
		(14 "In6.Cu" signal "L7VCC")
		(16 "In7.Cu" signal "L8VCC")
		(18 "In8.Cu" signal "L9GND")
		(20 "In9.Cu" signal "L10")
		(22 "In10.Cu" signal "L11GND")
		(24 "In11.Cu" signal "L12")
		(26 "In12.Cu" signal "L13GND")
		(2 "B.Cu" signal "BOTTOM")
		(9 "F.Adhes" user "F.Adhesive")
		(11 "B.Adhes" user "B.Adhesive")
		(13 "F.Paste" user "Package Geometry/Pastemask Top")
		(15 "B.Paste" user "Package Geometry/Pastemask Bottom")
		(5 "F.SilkS" user "Ref Des/Silkscreen Top")
		(7 "B.SilkS" user "Ref Des/Silkscreen Bottom")
		(1 "F.Mask" user "Board Geometry/Soldermask Top")
		(3 "B.Mask" user "Board Geometry/Soldermask Bottom")
		(17 "Dwgs.User" user "User.Drawings")
		(19 "Cmts.User" user "User.Comments")
		(21 "Eco1.User" user "User.Eco1")
		(23 "Eco2.User" user "User.Eco2")
		(25 "Edge.Cuts" user "Board Geometry/Outline")
		(27 "Margin" user)
		(31 "F.CrtYd" user "Package Geometry/Place Bound Top")
		(29 "B.CrtYd" user "Package Geometry/Place Bound Bottom")
		(35 "F.Fab" user "Ref Des/Assembly Top")
		(33 "B.Fab" user "Ref Des/Assembly Bottom")
	)
	(footprint ""
		(layer "F.Cu")
		(at 435.727094 -150.043642)
		(property "Reference" "R25W170"
			(at -0.8382 -0.677926 0)
			(unlocked yes)
			(layer "F.SilkS")
			(effects
				(font
					(size 0.4064 0.254)
					(thickness 0.1524)
				)
				(justify left)
			)
		)
		(property "Value" ""
			(at 0 0 0)
			(layer "F.Fab")
			(effects
				(font
					(size 1.27 1.27)
				)
			)
		)
		(duplicate_pad_numbers_are_jumpers no)
		(fp_poly
			(pts
				(xy -0.2794 -0.1016) (xy 0.2794 -0.1016) (xy 0.2794 0.9906) (xy -0.2794 0.9906)
			)
			(stroke
				(width 0)
				(type default)
			)
			(fill no)
			(layer "F.CrtYd")
		)
		(fp_line
			(start -0.2794 -0.1016)
			(end -0.2794 0.9906)
			(stroke
				(width 0.1)
				(type default)
			)
			(layer "F.Fab")
		)
		(fp_line
			(start -0.2794 0.9906)
			(end 0.2794 0.9906)
			(stroke
				(width 0.1)
				(type default)
			)
			(layer "F.Fab")
		)
		(fp_line
			(start 0.2794 -0.1016)
			(end -0.2794 -0.1016)
			(stroke
				(width 0.1)
				(type default)
			)
			(layer "F.Fab")
		)
		(fp_line
			(start 0.2794 0.9906)
			(end 0.2794 -0.1016)
			(stroke
				(width 0.1)
				(type default)
			)
			(layer "F.Fab")
		)
		(pad "1" smd rect
			(at 0 0)
			(size 0.508 0.508)
			(layers "F.Cu" "F.Mask" "F.Paste")
			(net "JTAG_BMC_TRST_BUF_N")
		)
		(pad "2" smd rect
			(at 0 0.889)
			(size 0.508 0.508)
			(layers "F.Cu" "F.Mask" "F.Paste")
			(net "GND")
		)
		(zone
			(layer "F.Cu")
			(hatch none 0.5)
			(connect_pads
				(clearance 0)
			)
			(min_thickness 0.25)
			(keepout
				(tracks allowed)
				(vias not_allowed)
				(pads allowed)
				(copperpour not_allowed)
				(footprints allowed)
			)
			(placement
				(enabled no)
				(sheetname "")
			)
			(fill
				(thermal_gap 0.5)
				(thermal_bridge_width 0.5)
				(island_removal_mode 0)
			)
			(polygon
				(pts
					(xy 435.473094 -149.789642) (xy 435.981094 -149.789642) (xy 435.981094 -149.408642) (xy 435.473094 -149.408642)
				)
			)
		)
		(zone
			(layer "F.Cu")
			(hatch none 0.5)
			(connect_pads
				(clearance 0)
			)
			(min_thickness 0.25)
			(keepout
				(tracks not_allowed)
				(vias allowed)
				(pads allowed)
				(copperpour not_allowed)
				(footprints allowed)
			)
			(placement
				(enabled no)
				(sheetname "")
			)
			(fill
				(thermal_gap 0.5)
				(thermal_bridge_width 0.5)
				(island_removal_mode 0)
			)
			(polygon
				(pts
					(xy 435.473094 -149.408642) (xy 435.981094 -149.408642) (xy 435.981094 -149.789642) (xy 435.473094 -149.789642)
				)
			)
		)
	)
	(footprint ""
		(layer "F.Cu")
		(at 175.387 -77.597 90)
		(property "Reference" "R4D25"
			(at 0 0 90)
			(layer "F.SilkS")
			(hide yes)
			(effects
				(font
					(size 1.27 1.27)
				)
			)
		)
		(property "Value" ""
			(at 0 0 90)
			(layer "F.Fab")
			(effects
				(font
					(size 1.27 1.27)
				)
			)
		)
		(duplicate_pad_numbers_are_jumpers no)
		(fp_poly
			(pts
				(xy -0.2794 -0.1016) (xy 0.2794 -0.1016) (xy 0.2794 0.9906) (xy -0.2794 0.9906)
			)
			(stroke
				(width 0)
				(type default)
			)
			(fill no)
			(layer "F.CrtYd")
		)
		(fp_line
			(start 0.2794 -0.1016)
			(end -0.2794 -0.1016)
			(stroke
				(width 0.1)
				(type default)
			)
			(layer "F.Fab")
		)
		(fp_line
			(start -0.2794 -0.1016)
			(end -0.2794 0.9906)
			(stroke
				(width 0.1)
				(type default)
			)
			(layer "F.Fab")
		)
		(fp_line
			(start 0.2794 0.9906)
			(end 0.2794 -0.1016)
			(stroke
				(width 0.1)
				(type default)
			)
			(layer "F.Fab")
		)
		(fp_line
			(start -0.2794 0.9906)
			(end 0.2794 0.9906)
			(stroke
				(width 0.1)
				(type default)
			)
			(layer "F.Fab")
		)
		(pad "1" smd rect
			(at 0 0 90)
			(size 0.508 0.508)
			(layers "F.Cu" "F.Mask" "F.Paste")
			(net "CLK_100M_CPU0_BCLK0_R_DN")
		)
		(pad "2" smd rect
			(at 0 0.889 90)
			(size 0.508 0.508)
			(layers "F.Cu" "F.Mask" "F.Paste")
			(net "CLK_100M_CPU0_BCLK0_DN")
		)
		(zone
			(layer "F.Cu")
			(hatch none 0.5)
			(connect_pads
				(clearance 0)
			)
			(min_thickness 0.25)
			(keepout
				(tracks allowed)
				(vias not_allowed)
				(pads allowed)
				(copperpour not_allowed)
				(footprints allowed)
			)
			(placement
				(enabled no)
				(sheetname "")
			)
			(fill
				(thermal_gap 0.5)
				(thermal_bridge_width 0.5)
				(island_removal_mode 0)
			)
			(polygon
				(pts
					(xy 175.641 -77.343) (xy 175.641 -77.851) (xy 176.022 -77.851) (xy 176.022 -77.343)
				)
			)
		)
		(zone
			(layer "F.Cu")
			(hatch none 0.5)
			(connect_pads
				(clearance 0)
			)
			(min_thickness 0.25)
			(keepout
				(tracks not_allowed)
				(vias allowed)
				(pads allowed)
				(copperpour not_allowed)
				(footprints allowed)
			)
			(placement
				(enabled no)
				(sheetname "")
			)
			(fill
				(thermal_gap 0.5)
				(thermal_bridge_width 0.5)
				(island_removal_mode 0)
			)
			(polygon
				(pts
					(xy 176.022 -77.343) (xy 176.022 -77.851) (xy 175.641 -77.851) (xy 175.641 -77.343)
				)
			)
		)
	)
	(footprint ""
		(layer "F.Cu")
		(at 349.735648 -21.279612)
		(property "Reference" "R12W1"
			(at 0 0 0)
			(layer "F.SilkS")
			(hide yes)
			(effects
				(font
					(size 1.27 1.27)
				)
			)
		)
		(property "Value" "*"
			(at 0 -8.9535 0)
			(unlocked yes)
			(layer "F.Fab")
			(hide yes)
			(effects
				(font
					(size 1.27 1.016)
					(thickness 0.1524)
				)
			)
		)
		(property "Device Type" "665KR5B-1-GP_SMD-RG3-665KR5B-1A"
			(at 0 -10.6299 0)
			(unlocked yes)
			(layer "F.Fab")
			(hide yes)
			(effects
				(font
					(size 1.27 1.016)
					(thickness 0.1524)
				)
			)
		)
		(duplicate_pad_numbers_are_jumpers no)
		(fp_line
			(start -0.889 -1.7018)
			(end -0.889 0.2794)
			(stroke
				(width 0.1524)
				(type default)
			)
			(layer "F.SilkS")
		)
		(fp_line
			(start -0.889 0.0762)
			(end -0.889 1.7018)
			(stroke
				(width 0.1524)
				(type default)
			)
			(layer "F.SilkS")
		)
		(fp_line
			(start -0.889 1.7018)
			(end 0.889 1.7018)
			(stroke
				(width 0.1524)
				(type default)
			)
			(layer "F.SilkS")
		)
		(fp_line
			(start 0.889 -1.7018)
			(end -0.889 -1.7018)
			(stroke
				(width 0.1524)
				(type default)
			)
			(layer "F.SilkS")
		)
		(fp_line
			(start 0.889 -1.7018)
			(end 0.889 -0.381)
			(stroke
				(width 0.1524)
				(type default)
			)
			(layer "F.SilkS")
		)
		(fp_line
			(start 0.889 1.7018)
			(end 0.889 -0.508)
			(stroke
				(width 0.1524)
				(type default)
			)
			(layer "F.SilkS")
		)
		(fp_poly
			(pts
				(xy 0.9652 -1.778) (xy 0.9652 1.778) (xy -0.9652 1.778) (xy -0.9652 -1.778)
			)
			(stroke
				(width 0)
				(type default)
			)
			(fill no)
			(layer "F.CrtYd")
		)
		(fp_rect
			(start -0.9652 1.778)
			(end 0.9652 -1.778)
			(stroke
				(width 0)
				(type default)
			)
			(fill no)
			(layer "F.Fab")
		)
		(pad "1" smd rect
			(at 0 -0.9652)
			(size 1.397 1.143)
			(layers "F.Cu" "F.Mask" "F.Paste")
			(net "P12V_STBY")
		)
		(pad "2" smd rect
			(at 0 0.9652)
			(size 1.397 1.143)
			(layers "F.Cu" "F.Mask" "F.Paste")
			(net "VR_PVDDQ_ABC_AIINSEN")
		)
	)
)
